(kicad_pcb
	(version 20260206)
	(generator "pcbnew")
	(generator_version "10.0")
	(general
		(thickness 1.6)
		(legacy_teardrops no)
	)
	(paper "A4")
	(title_block
		(title "01162023_DA0F0TEBIF0_F0T_Expander_BD_F_brd_V02_OCP.brd")
		(comment 1 "Grand Teton / footprints 9392-9400 of 9728")
	)
	(layers
		(0 "F.Cu" signal "TOP")
		(4 "In1.Cu" signal "GND")
		(6 "In2.Cu" signal "VCC")
		(8 "In3.Cu" signal "VCC1")
		(10 "In4.Cu" signal "GND1")
		(12 "In5.Cu" signal "IN1")
		(14 "In6.Cu" signal "GND2")
		(16 "In7.Cu" signal "IN2")
		(18 "In8.Cu" signal "GND3")
		(20 "In9.Cu" signal "IN3")
		(22 "In10.Cu" signal "GND4")
		(24 "In11.Cu" signal "IN4")
		(26 "In12.Cu" signal "GND5")
		(28 "In13.Cu" signal "IN5")
		(30 "In14.Cu" signal "GND6")
		(32 "In15.Cu" signal "IN6")
		(34 "In16.Cu" signal "GND7")
		(2 "B.Cu" signal "BOTTOM")
		(9 "F.Adhes" user "F.Adhesive")
		(11 "B.Adhes" user "B.Adhesive")
		(13 "F.Paste" user "Package Geometry/Pastemask Top")
		(15 "B.Paste" user "Package Geometry/Pastemask Bottom")
		(5 "F.SilkS" user "Ref Des/Silkscreen Top")
		(7 "B.SilkS" user "Ref Des/Silkscreen Bottom")
		(1 "F.Mask" user "Board Geometry/Soldermask Top")
		(3 "B.Mask" user "Board Geometry/Soldermask Bottom")
		(17 "Dwgs.User" user "User.Drawings")
		(19 "Cmts.User" user "User.Comments")
		(21 "Eco1.User" user "User.Eco1")
		(23 "Eco2.User" user "User.Eco2")
		(25 "Edge.Cuts" user "Board Geometry/Outline")
		(27 "Margin" user)
		(31 "F.CrtYd" user "Package Geometry/Place Bound Top")
		(29 "B.CrtYd" user "Package Geometry/Place Bound Bottom")
		(35 "F.Fab" user "Ref Des/Assembly Top")
		(33 "B.Fab" user "Ref Des/Assembly Bottom")
	)
	(footprint ""
		(layer "B.Cu")
		(at 133.030214 -206.666846 -90)
		(property "Reference" "C2586"
			(at 0 0 90)
			(layer "B.SilkS")
			(hide yes)
			(effects
				(font
					(size 1.27 1.27)
				)
				(justify mirror)
			)
		)
		(property "Value" ""
			(at 0 0 90)
			(layer "B.Fab")
			(effects
				(font
					(size 1.27 1.27)
				)
				(justify mirror)
			)
		)
		(duplicate_pad_numbers_are_jumpers no)
		(fp_line
			(start -1.2954 0.5842)
			(end 1.2954 0.5842)
			(stroke
				(width 0.1524)
				(type default)
			)
			(layer "B.SilkS")
		)
		(fp_line
			(start 1.2954 0.5842)
			(end 1.2954 -0.5842)
			(stroke
				(width 0.1524)
				(type default)
			)
			(layer "B.SilkS")
		)
		(fp_line
			(start -1.2954 -0.5842)
			(end -1.2954 0.5842)
			(stroke
				(width 0.1524)
				(type default)
			)
			(layer "B.SilkS")
		)
		(fp_line
			(start 1.2954 -0.5842)
			(end -1.2954 -0.5842)
			(stroke
				(width 0.1524)
				(type default)
			)
			(layer "B.SilkS")
		)
		(fp_line
			(start -0.8636 0.4572)
			(end 0.8636 0.4572)
			(stroke
				(width 0.1)
				(type default)
			)
			(layer "B.Fab")
		)
		(fp_line
			(start 0.8636 0.4572)
			(end 0.8636 0.4064)
			(stroke
				(width 0.1)
				(type default)
			)
			(layer "B.Fab")
		)
		(fp_line
			(start -1.1938 0.4064)
			(end -0.8636 0.4064)
			(stroke
				(width 0.1)
				(type default)
			)
			(layer "B.Fab")
		)
		(fp_line
			(start -0.8636 0.4064)
			(end -0.8636 0.4572)
			(stroke
				(width 0.1)
				(type default)
			)
			(layer "B.Fab")
		)
		(fp_line
			(start 0.8636 0.4064)
			(end 1.1938 0.4064)
			(stroke
				(width 0.1)
				(type default)
			)
			(layer "B.Fab")
		)
		(fp_line
			(start 1.1938 0.4064)
			(end 1.1938 -0.4064)
			(stroke
				(width 0.1)
				(type default)
			)
			(layer "B.Fab")
		)
		(fp_line
			(start -1.1938 -0.4064)
			(end -1.1938 0.4064)
			(stroke
				(width 0.1)
				(type default)
			)
			(layer "B.Fab")
		)
		(fp_line
			(start -0.8636 -0.4064)
			(end -1.1938 -0.4064)
			(stroke
				(width 0.1)
				(type default)
			)
			(layer "B.Fab")
		)
		(fp_line
			(start 0.8636 -0.4064)
			(end 0.8636 -0.4572)
			(stroke
				(width 0.1)
				(type default)
			)
			(layer "B.Fab")
		)
		(fp_line
			(start 1.1938 -0.4064)
			(end 0.8636 -0.4064)
			(stroke
				(width 0.1)
				(type default)
			)
			(layer "B.Fab")
		)
		(fp_line
			(start -0.8636 -0.4572)
			(end -0.8636 -0.4064)
			(stroke
				(width 0.1)
				(type default)
			)
			(layer "B.Fab")
		)
		(fp_line
			(start 0.8636 -0.4572)
			(end -0.8636 -0.4572)
			(stroke
				(width 0.1)
				(type default)
			)
			(layer "B.Fab")
		)
		(pad "1" smd rect
			(at 0.7366 0 180)
			(size 0.7112 0.8128)
			(layers "B.Cu" "B.Mask" "B.Paste")
			(net "P3V3_AUX")
		)
		(pad "2" smd rect
			(at -0.7366 0 180)
			(size 0.7112 0.8128)
			(layers "B.Cu" "B.Mask" "B.Paste")
			(net "GND")
		)
	)
	(footprint ""
		(layer "B.Cu")
		(at 397.49984 -300.174914)
		(property "Reference" "C1894"
			(at 0 0 0)
			(layer "B.SilkS")
			(hide yes)
			(effects
				(font
					(size 1.27 1.27)
				)
				(justify mirror)
			)
		)
		(property "Value" ""
			(at 0 0 0)
			(layer "B.Fab")
			(effects
				(font
					(size 1.27 1.27)
				)
				(justify mirror)
			)
		)
		(duplicate_pad_numbers_are_jumpers no)
		(fp_line
			(start -0.299974 -0.150114)
			(end -0.299974 0.150114)
			(stroke
				(width 0.1)
				(type default)
			)
			(layer "B.Fab")
		)
		(fp_line
			(start -0.299974 0.150114)
			(end 0.299974 0.150114)
			(stroke
				(width 0.1)
				(type default)
			)
			(layer "B.Fab")
		)
		(fp_line
			(start 0.299974 -0.150114)
			(end -0.299974 -0.150114)
			(stroke
				(width 0.1)
				(type default)
			)
			(layer "B.Fab")
		)
		(fp_line
			(start 0.299974 0.150114)
			(end 0.299974 -0.150114)
			(stroke
				(width 0.1)
				(type default)
			)
			(layer "B.Fab")
		)
		(pad "1" smd rect
			(at 0.2667 0 180)
			(size 0.3048 0.381)
			(layers "B.Cu" "B.Mask" "B.Paste")
			(net "P0V8_PEX3")
		)
		(pad "2" smd rect
			(at -0.2667 0 180)
			(size 0.3048 0.381)
			(layers "B.Cu" "B.Mask" "B.Paste")
			(net "GND")
		)
	)
	(footprint ""
		(layer "B.Cu")
		(at 416.708082 -299.224954 180)
		(property "Reference" "C1931"
			(at 0 0 0)
			(layer "B.SilkS")
			(hide yes)
			(effects
				(font
					(size 1.27 1.27)
				)
				(justify mirror)
			)
		)
		(property "Value" ""
			(at 0 0 0)
			(layer "B.Fab")
			(effects
				(font
					(size 1.27 1.27)
				)
				(justify mirror)
			)
		)
		(duplicate_pad_numbers_are_jumpers no)
		(fp_line
			(start 0.299974 0.150114)
			(end 0.299974 -0.150114)
			(stroke
				(width 0.1)
				(type default)
			)
			(layer "B.Fab")
		)
		(fp_line
			(start 0.299974 -0.150114)
			(end -0.299974 -0.150114)
			(stroke
				(width 0.1)
				(type default)
			)
			(layer "B.Fab")
		)
		(fp_line
			(start -0.299974 0.150114)
			(end 0.299974 0.150114)
			(stroke
				(width 0.1)
				(type default)
			)
			(layer "B.Fab")
		)
		(fp_line
			(start -0.299974 -0.150114)
			(end -0.299974 0.150114)
			(stroke
				(width 0.1)
				(type default)
			)
			(layer "B.Fab")
		)
		(pad "1" smd rect
			(at 0.2667 0)
			(size 0.3048 0.381)
			(layers "B.Cu" "B.Mask" "B.Paste")
			(net "P0V8_SERDES_VDDA_PEX3")
		)
		(pad "2" smd rect
			(at -0.2667 0)
			(size 0.3048 0.381)
			(layers "B.Cu" "B.Mask" "B.Paste")
			(net "GND")
		)
	)
	(footprint ""
		(layer "B.Cu")
		(at 104.932734 -237.306612 -90)
		(property "Reference" "PC1003"
			(at 0 0 90)
			(layer "B.SilkS")
			(hide yes)
			(effects
				(font
					(size 1.27 1.27)
				)
				(justify mirror)
			)
		)
		(property "Value" ""
			(at 0 0 90)
			(layer "B.Fab")
			(effects
				(font
					(size 1.27 1.27)
				)
				(justify mirror)
			)
		)
		(duplicate_pad_numbers_are_jumpers no)
		(fp_line
			(start -1.524 0.762)
			(end 1.524 0.762)
			(stroke
				(width 0.1524)
				(type default)
			)
			(layer "B.SilkS")
		)
		(fp_line
			(start 1.524 0.762)
			(end 1.524 -0.762)
			(stroke
				(width 0.1524)
				(type default)
			)
			(layer "B.SilkS")
		)
		(fp_line
			(start -1.524 -0.762)
			(end -1.524 0.762)
			(stroke
				(width 0.1524)
				(type default)
			)
			(layer "B.SilkS")
		)
		(fp_line
			(start 1.524 -0.762)
			(end -1.524 -0.762)
			(stroke
				(width 0.1524)
				(type default)
			)
			(layer "B.SilkS")
		)
		(fp_line
			(start -1.1049 0.724916)
			(end -1.1049 -0.724916)
			(stroke
				(width 0.1)
				(type default)
			)
			(layer "B.Fab")
		)
		(fp_line
			(start 1.1049 0.724916)
			(end -1.1049 0.724916)
			(stroke
				(width 0.1)
				(type default)
			)
			(layer "B.Fab")
		)
		(fp_line
			(start -1.1049 -0.724916)
			(end 1.1049 -0.724916)
			(stroke
				(width 0.1)
				(type default)
			)
			(layer "B.Fab")
		)
		(fp_line
			(start 1.1049 -0.724916)
			(end 1.1049 0.724916)
			(stroke
				(width 0.1)
				(type default)
			)
			(layer "B.Fab")
		)
		(pad "1" smd rect
			(at 0.889 0 270)
			(size 1.016 1.27)
			(layers "B.Cu" "B.Mask" "B.Paste")
			(net "P1V8_PEX_R")
		)
		(pad "2" smd rect
			(at -0.889 0 270)
			(size 1.016 1.27)
			(layers "B.Cu" "B.Mask" "B.Paste")
			(net "GND")
		)
	)
	(footprint ""
		(layer "B.Cu")
		(at 322.512182 -219.956888 90)
		(property "Reference" "R6284"
			(at 0 0 90)
			(layer "B.SilkS")
			(hide yes)
			(effects
				(font
					(size 1.27 1.27)
				)
				(justify mirror)
			)
		)
		(property "Value" ""
			(at 0 0 90)
			(layer "B.Fab")
			(effects
				(font
					(size 1.27 1.27)
				)
				(justify mirror)
			)
		)
		(duplicate_pad_numbers_are_jumpers no)
		(fp_line
			(start 0.7874 -0.4064)
			(end -0.7874 -0.4064)
			(stroke
				(width 0.1524)
				(type default)
			)
			(layer "B.SilkS")
		)
		(fp_line
			(start -0.7874 -0.4064)
			(end -0.7874 0.4064)
			(stroke
				(width 0.1524)
				(type default)
			)
			(layer "B.SilkS")
		)
		(fp_line
			(start 0.7874 0.4064)
			(end 0.7874 -0.4064)
			(stroke
				(width 0.1524)
				(type default)
			)
			(layer "B.SilkS")
		)
		(fp_line
			(start -0.7874 0.4064)
			(end 0.7874 0.4064)
			(stroke
				(width 0.1524)
				(type default)
			)
			(layer "B.SilkS")
		)
		(fp_line
			(start 0.67945 -0.305054)
			(end 0.12065 -0.305054)
			(stroke
				(width 0.1)
				(type default)
			)
			(layer "B.Fab")
		)
		(fp_line
			(start 0.12065 -0.305054)
			(end 0.12065 -0.2794)
			(stroke
				(width 0.1)
				(type default)
			)
			(layer "B.Fab")
		)
		(fp_line
			(start -0.12065 -0.3048)
			(end -0.67945 -0.3048)
			(stroke
				(width 0.1)
				(type default)
			)
			(layer "B.Fab")
		)
		(fp_line
			(start -0.67945 -0.3048)
			(end -0.67945 0.3048)
			(stroke
				(width 0.1)
				(type default)
			)
			(layer "B.Fab")
		)
		(fp_line
			(start 0.12065 -0.2794)
			(end -0.12065 -0.2794)
			(stroke
				(width 0.1)
				(type default)
			)
			(layer "B.Fab")
		)
		(fp_line
			(start -0.12065 -0.2794)
			(end -0.12065 -0.3048)
			(stroke
				(width 0.1)
				(type default)
			)
			(layer "B.Fab")
		)
		(fp_line
			(start 0.12065 0.2794)
			(end 0.12065 0.3048)
			(stroke
				(width 0.1)
				(type default)
			)
			(layer "B.Fab")
		)
		(fp_line
			(start -0.120396 0.2794)
			(end 0.12065 0.2794)
			(stroke
				(width 0.1)
				(type default)
			)
			(layer "B.Fab")
		)
		(fp_line
			(start 0.67945 0.3048)
			(end 0.67945 -0.305054)
			(stroke
				(width 0.1)
				(type default)
			)
			(layer "B.Fab")
		)
		(fp_line
			(start 0.12065 0.3048)
			(end 0.67945 0.3048)
			(stroke
				(width 0.1)
				(type default)
			)
			(layer "B.Fab")
		)
		(fp_line
			(start -0.120396 0.3048)
			(end -0.120396 0.2794)
			(stroke
				(width 0.1)
				(type default)
			)
			(layer "B.Fab")
		)
		(fp_line
			(start -0.67945 0.3048)
			(end -0.120396 0.3048)
			(stroke
				(width 0.1)
				(type default)
			)
			(layer "B.Fab")
		)
		(pad "1" smd circle
			(at 0.40005 0 270)
			(size 0 0)
			(layers "B.Cu" "B.Mask" "B.Paste")
			(net "JTAG_FPGA_R_TDO")
		)
		(pad "2" smd circle
			(at -0.40005 0 270)
			(size 0 0)
			(layers "B.Cu" "B.Mask" "B.Paste")
			(net "JTAG_FPGA_TDO")
		)
	)
	(footprint ""
		(layer "B.Cu")
		(at 406.049988 -292.099746 90)
		(property "Reference" "C1997"
			(at 0 0 90)
			(layer "B.SilkS")
			(hide yes)
			(effects
				(font
					(size 1.27 1.27)
				)
				(justify mirror)
			)
		)
		(property "Value" ""
			(at 0 0 90)
			(layer "B.Fab")
			(effects
				(font
					(size 1.27 1.27)
				)
				(justify mirror)
			)
		)
		(duplicate_pad_numbers_are_jumpers no)
		(fp_line
			(start 0.299974 -0.150114)
			(end -0.299974 -0.150114)
			(stroke
				(width 0.1)
				(type default)
			)
			(layer "B.Fab")
		)
		(fp_line
			(start -0.299974 -0.150114)
			(end -0.299974 0.150114)
			(stroke
				(width 0.1)
				(type default)
			)
			(layer "B.Fab")
		)
		(fp_line
			(start 0.299974 0.150114)
			(end 0.299974 -0.150114)
			(stroke
				(width 0.1)
				(type default)
			)
			(layer "B.Fab")
		)
		(fp_line
			(start -0.299974 0.150114)
			(end 0.299974 0.150114)
			(stroke
				(width 0.1)
				(type default)
			)
			(layer "B.Fab")
		)
		(pad "1" smd rect
			(at 0.2667 0 270)
			(size 0.3048 0.381)
			(layers "B.Cu" "B.Mask" "B.Paste")
			(net "P0V8_SERDES_VDDA_PEX3")
		)
		(pad "2" smd rect
			(at -0.2667 0 270)
			(size 0.3048 0.381)
			(layers "B.Cu" "B.Mask" "B.Paste")
			(net "GND")
		)
	)
	(footprint ""
		(layer "B.Cu")
		(at 177.42027 -195.874386)
		(property "Reference" "R1034"
			(at 0 0 0)
			(layer "B.SilkS")
			(hide yes)
			(effects
				(font
					(size 1.27 1.27)
				)
				(justify mirror)
			)
		)
		(property "Value" ""
			(at 0 0 0)
			(layer "B.Fab")
			(effects
				(font
					(size 1.27 1.27)
				)
				(justify mirror)
			)
		)
		(duplicate_pad_numbers_are_jumpers no)
		(fp_line
			(start -0.7874 -0.4064)
			(end -0.7874 0.4064)
			(stroke
				(width 0.1524)
				(type default)
			)
			(layer "B.SilkS")
		)
		(fp_line
			(start -0.7874 0.4064)
			(end 0.7874 0.4064)
			(stroke
				(width 0.1524)
				(type default)
			)
			(layer "B.SilkS")
		)
		(fp_line
			(start 0.7874 -0.4064)
			(end -0.7874 -0.4064)
			(stroke
				(width 0.1524)
				(type default)
			)
			(layer "B.SilkS")
		)
		(fp_line
			(start 0.7874 0.4064)
			(end 0.7874 -0.4064)
			(stroke
				(width 0.1524)
				(type default)
			)
			(layer "B.SilkS")
		)
		(fp_line
			(start -0.67945 -0.3048)
			(end -0.67945 0.3048)
			(stroke
				(width 0.1)
				(type default)
			)
			(layer "B.Fab")
		)
		(fp_line
			(start -0.67945 0.3048)
			(end -0.120396 0.3048)
			(stroke
				(width 0.1)
				(type default)
			)
			(layer "B.Fab")
		)
		(fp_line
			(start -0.12065 -0.3048)
			(end -0.67945 -0.3048)
			(stroke
				(width 0.1)
				(type default)
			)
			(layer "B.Fab")
		)
		(fp_line
			(start -0.12065 -0.2794)
			(end -0.12065 -0.3048)
			(stroke
				(width 0.1)
				(type default)
			)
			(layer "B.Fab")
		)
		(fp_line
			(start -0.120396 0.2794)
			(end 0.12065 0.2794)
			(stroke
				(width 0.1)
				(type default)
			)
			(layer "B.Fab")
		)
		(fp_line
			(start -0.120396 0.3048)
			(end -0.120396 0.2794)
			(stroke
				(width 0.1)
				(type default)
			)
			(layer "B.Fab")
		)
		(fp_line
			(start 0.12065 -0.305054)
			(end 0.12065 -0.2794)
			(stroke
				(width 0.1)
				(type default)
			)
			(layer "B.Fab")
		)
		(fp_line
			(start 0.12065 -0.2794)
			(end -0.12065 -0.2794)
			(stroke
				(width 0.1)
				(type default)
			)
			(layer "B.Fab")
		)
		(fp_line
			(start 0.12065 0.2794)
			(end 0.12065 0.3048)
			(stroke
				(width 0.1)
				(type default)
			)
			(layer "B.Fab")
		)
		(fp_line
			(start 0.12065 0.3048)
			(end 0.67945 0.3048)
			(stroke
				(width 0.1)
				(type default)
			)
			(layer "B.Fab")
		)
		(fp_line
			(start 0.67945 -0.305054)
			(end 0.12065 -0.305054)
			(stroke
				(width 0.1)
				(type default)
			)
			(layer "B.Fab")
		)
		(fp_line
			(start 0.67945 0.3048)
			(end 0.67945 -0.305054)
			(stroke
				(width 0.1)
				(type default)
			)
			(layer "B.Fab")
		)
		(pad "1" smd circle
			(at 0.40005 0 180)
			(size 0 0)
			(layers "B.Cu" "B.Mask" "B.Paste")
			(net "GND")
		)
		(pad "2" smd circle
			(at -0.40005 0 180)
			(size 0 0)
			(layers "B.Cu" "B.Mask" "B.Paste")
			(net "SPI_BIC1_CLK_LS01_DIR2")
		)
	)
	(footprint ""
		(layer "B.Cu")
		(at 394.64996 -290.674806)
		(property "Reference" "C3523"
			(at 0 0 0)
			(layer "B.SilkS")
			(hide yes)
			(effects
				(font
					(size 1.27 1.27)
				)
				(justify mirror)
			)
		)
		(property "Value" ""
			(at 0 0 0)
			(layer "B.Fab")
			(effects
				(font
					(size 1.27 1.27)
				)
				(justify mirror)
			)
		)
		(duplicate_pad_numbers_are_jumpers no)
		(fp_line
			(start -0.299974 -0.150114)
			(end -0.299974 0.150114)
			(stroke
				(width 0.1)
				(type default)
			)
			(layer "B.Fab")
		)
		(fp_line
			(start -0.299974 0.150114)
			(end 0.299974 0.150114)
			(stroke
				(width 0.1)
				(type default)
			)
			(layer "B.Fab")
		)
		(fp_line
			(start 0.299974 -0.150114)
			(end -0.299974 -0.150114)
			(stroke
				(width 0.1)
				(type default)
			)
			(layer "B.Fab")
		)
		(fp_line
			(start 0.299974 0.150114)
			(end 0.299974 -0.150114)
			(stroke
				(width 0.1)
				(type default)
			)
			(layer "B.Fab")
		)
		(pad "1" smd rect
			(at 0.2667 0 180)
			(size 0.3048 0.381)
			(layers "B.Cu" "B.Mask" "B.Paste")
			(net "P1V8_PEX")
		)
		(pad "2" smd rect
			(at -0.2667 0 180)
			(size 0.3048 0.381)
			(layers "B.Cu" "B.Mask" "B.Paste")
			(net "GND")
		)
	)
	(footprint ""
		(layer "B.Cu")
		(at 248.353834 -223.937068 90)
		(property "Reference" "R3478"
			(at 0 0 90)
			(layer "B.SilkS")
			(hide yes)
			(effects
				(font
					(size 1.27 1.27)
				)
				(justify mirror)
			)
		)
		(property "Value" ""
			(at 0 0 90)
			(layer "B.Fab")
			(effects
				(font
					(size 1.27 1.27)
				)
				(justify mirror)
			)
		)
		(duplicate_pad_numbers_are_jumpers no)
		(fp_line
			(start 0.7874 -0.4064)
			(end -0.7874 -0.4064)
			(stroke
				(width 0.1524)
				(type default)
			)
			(layer "B.SilkS")
		)
		(fp_line
			(start -0.7874 -0.4064)
			(end -0.7874 0.4064)
			(stroke
				(width 0.1524)
				(type default)
			)
			(layer "B.SilkS")
		)
		(fp_line
			(start 0.7874 0.4064)
			(end 0.7874 -0.4064)
			(stroke
				(width 0.1524)
				(type default)
			)
			(layer "B.SilkS")
		)
		(fp_line
			(start -0.7874 0.4064)
			(end 0.7874 0.4064)
			(stroke
				(width 0.1524)
				(type default)
			)
			(layer "B.SilkS")
		)
		(fp_line
			(start 0.67945 -0.305054)
			(end 0.12065 -0.305054)
			(stroke
				(width 0.1)
				(type default)
			)
			(layer "B.Fab")
		)
		(fp_line
			(start 0.12065 -0.305054)
			(end 0.12065 -0.2794)
			(stroke
				(width 0.1)
				(type default)
			)
			(layer "B.Fab")
		)
		(fp_line
			(start -0.12065 -0.3048)
			(end -0.67945 -0.3048)
			(stroke
				(width 0.1)
				(type default)
			)
			(layer "B.Fab")
		)
		(fp_line
			(start -0.67945 -0.3048)
			(end -0.67945 0.3048)
			(stroke
				(width 0.1)
				(type default)
			)
			(layer "B.Fab")
		)
		(fp_line
			(start 0.12065 -0.2794)
			(end -0.12065 -0.2794)
			(stroke
				(width 0.1)
				(type default)
			)
			(layer "B.Fab")
		)
		(fp_line
			(start -0.12065 -0.2794)
			(end -0.12065 -0.3048)
			(stroke
				(width 0.1)
				(type default)
			)
			(layer "B.Fab")
		)
		(fp_line
			(start 0.12065 0.2794)
			(end 0.12065 0.3048)
			(stroke
				(width 0.1)
				(type default)
			)
			(layer "B.Fab")
		)
		(fp_line
			(start -0.120396 0.2794)
			(end 0.12065 0.2794)
			(stroke
				(width 0.1)
				(type default)
			)
			(layer "B.Fab")
		)
		(fp_line
			(start 0.67945 0.3048)
			(end 0.67945 -0.305054)
			(stroke
				(width 0.1)
				(type default)
			)
			(layer "B.Fab")
		)
		(fp_line
			(start 0.12065 0.3048)
			(end 0.67945 0.3048)
			(stroke
				(width 0.1)
				(type default)
			)
			(layer "B.Fab")
		)
		(fp_line
			(start -0.120396 0.3048)
			(end -0.120396 0.2794)
			(stroke
				(width 0.1)
				(type default)
			)
			(layer "B.Fab")
		)
		(fp_line
			(start -0.67945 0.3048)
			(end -0.120396 0.3048)
			(stroke
				(width 0.1)
				(type default)
			)
			(layer "B.Fab")
		)
		(pad "1" smd circle
			(at 0.40005 0 270)
			(size 0 0)
			(layers "B.Cu" "B.Mask" "B.Paste")
			(net "SPI_MUX_PEX2_EN_N")
		)
		(pad "2" smd circle
			(at -0.40005 0 270)
			(size 0 0)
			(layers "B.Cu" "B.Mask" "B.Paste")
			(net "GND")
		)
	)
)
